(kicad_pcb
	(version 20241229)
	(generator "pcbnew")
	(generator_version "9.0")
	(general
		(thickness 1.711)
		(legacy_teardrops no)
	)
	(paper "A4")
	(title_block
		(title "Antmicro Baseboard for Jetson AGX Thor")
		(date "2026-02-18")
		(rev "1.1.0")
		(company "Antmicro Ltd")
		(comment 1 "www.antmicro.com")
		(comment 9 "footprints 623-628 of 1170")
	)
	(layers
		(0 "F.Cu" signal)
		(4 "In1.Cu" signal)
		(6 "In2.Cu" signal)
		(8 "In3.Cu" signal)
		(10 "In4.Cu" jumper)
		(12 "In5.Cu" signal)
		(14 "In6.Cu" signal)
		(16 "In7.Cu" signal)
		(18 "In8.Cu" signal)
		(2 "B.Cu" signal)
		(9 "F.Adhes" user "F.Adhesive")
		(11 "B.Adhes" user "B.Adhesive")
		(13 "F.Paste" user)
		(15 "B.Paste" user)
		(5 "F.SilkS" user "F.Silkscreen")
		(7 "B.SilkS" user "B.Silkscreen")
		(1 "F.Mask" user)
		(3 "B.Mask" user)
		(17 "Dwgs.User" user "User.Drawings")
		(19 "Cmts.User" user "User.Comments")
		(21 "Eco1.User" user "User.Eco1")
		(23 "Eco2.User" user "User.Eco2")
		(25 "Edge.Cuts" user)
		(27 "Margin" user)
		(31 "F.CrtYd" user "F.Courtyard")
		(29 "B.CrtYd" user "B.Courtyard")
		(35 "F.Fab" user)
		(33 "B.Fab" user)
	)
	(footprint "antmicro-footprints:R_0402_1005Metric"
		(layer "B.Cu")
		(at 104.9 64.5 -90)
		(descr "Resistor SMD 0402")
		(tags "resistor SMD 0402")
		(property "Reference" "R2"
			(at -2.5 -0.48 90)
			(layer "B.SilkS")
			(effects
				(font
					(size 0.7 0.7)
					(thickness 0.15)
				)
				(justify left bottom mirror)
			)
		)
		(property "Value" "R_33R_0402"
			(at -1.011843 -1.772047 90)
			(layer "B.Fab")
			(effects
				(font
					(size 0.7 0.7)
					(thickness 0.15)
				)
				(justify left bottom mirror)
			)
		)
		(property "Datasheet" "https://www.bourns.com/docs/product-datasheets/cr.pdf"
			(at 0 0 90)
			(layer "B.Fab")
			(hide yes)
			(effects
				(font
					(size 1.27 1.27)
					(thickness 0.15)
				)
				(justify mirror)
			)
		)
		(property "Description" "SMD Chip Resistor, 33 ohm, ± 1%, 62.5 mW, 0402 [1005 Metric], Thick Film, General Purpose"
			(at 0 0 90)
			(layer "B.Fab")
			(hide yes)
			(effects
				(font
					(size 1.27 1.27)
					(thickness 0.15)
				)
				(justify mirror)
			)
		)
		(property "MPN" "CR0402-FX-33R0GLF"
			(at 0 0 90)
			(unlocked yes)
			(layer "B.Fab")
			(hide yes)
			(effects
				(font
					(size 1 1)
					(thickness 0.15)
				)
				(justify mirror)
			)
		)
		(property "Manufacturer" "Bourns"
			(at 0 0 90)
			(unlocked yes)
			(layer "B.Fab")
			(hide yes)
			(effects
				(font
					(size 1 1)
					(thickness 0.15)
				)
				(justify mirror)
			)
		)
		(property "License" "Apache-2.0"
			(at 0 0 90)
			(unlocked yes)
			(layer "B.Fab")
			(hide yes)
			(effects
				(font
					(size 1 1)
					(thickness 0.15)
				)
				(justify mirror)
			)
		)
		(property "Author" "Antmicro"
			(at 0 0 90)
			(unlocked yes)
			(layer "B.Fab")
			(hide yes)
			(effects
				(font
					(size 1 1)
					(thickness 0.15)
				)
				(justify mirror)
			)
		)
		(property "Val" "33R"
			(at 0 0 90)
			(unlocked yes)
			(layer "B.Fab")
			(hide yes)
			(effects
				(font
					(size 1 1)
					(thickness 0.15)
				)
				(justify mirror)
			)
		)
		(property "Tolerance" "1%"
			(at 0 0 90)
			(unlocked yes)
			(layer "B.Fab")
			(hide yes)
			(effects
				(font
					(size 1 1)
					(thickness 0.15)
				)
				(justify mirror)
			)
		)
		(sheetname "/SoM_IO2/")
		(sheetfile "som_io2.kicad_sch")
		(attr smd)
		(fp_rect
			(start -0.925 0.47)
			(end 0.925 -0.47)
			(stroke
				(width 0.05)
				(type default)
			)
			(fill no)
			(layer "B.CrtYd")
		)
		(fp_rect
			(start -0.5 0.25)
			(end 0.5 -0.25)
			(stroke
				(width 0.15)
				(type solid)
			)
			(fill no)
			(layer "B.Fab")
		)
		(fp_text user "${REFERENCE}"
			(at -0.95 -3.168 90)
			(layer "B.Fab")
			(effects
				(font
					(size 0.7 0.7)
					(thickness 0.15)
				)
				(justify left bottom mirror)
			)
		)
		(fp_text user "License: Apache-2.0"
			(at -0.95 -5.169 90)
			(layer "B.Fab")
			(effects
				(font
					(size 0.7 0.7)
					(thickness 0.15)
				)
				(justify left bottom mirror)
			)
		)
		(fp_text user "Author: Antmicro"
			(at -0.95 -4.169 90)
			(layer "B.Fab")
			(effects
				(font
					(size 0.7 0.7)
					(thickness 0.15)
				)
				(justify left bottom mirror)
			)
		)
		(pad "1" smd roundrect
			(at -0.48 0 270)
			(size 0.59 0.64)
			(layers "B.Cu" "B.Mask" "B.Paste")
			(roundrect_rratio 0.25)
			(net 894 "/SoM_IO2/SFI_CLK+")
			(pintype "passive")
		)
		(pad "2" smd roundrect
			(at 0.48 0 270)
			(size 0.59 0.64)
			(layers "B.Cu" "B.Mask" "B.Paste")
			(roundrect_rratio 0.25)
			(net 169 "/SoM_IO2/SFI_REFCLK+")
			(pintype "passive")
		)
	)
	(footprint "antmicro-footprints:R_0402_1005Metric"
		(layer "B.Cu")
		(at 108.555 138.43 90)
		(descr "Resistor SMD 0402")
		(tags "resistor SMD 0402")
		(property "Reference" "R222"
			(at -1.35 -2.795 90)
			(layer "B.SilkS")
			(effects
				(font
					(size 0.7 0.7)
					(thickness 0.15)
				)
				(justify right top mirror)
			)
		)
		(property "Value" "R_200R_0402"
			(at -1.011843 -1.772047 90)
			(layer "B.Fab")
			(effects
				(font
					(size 0.7 0.7)
					(thickness 0.15)
				)
				(justify right top mirror)
			)
		)
		(property "Datasheet" "https://www.bourns.com/docs/product-datasheets/cr.pdf"
			(at 0 0 90)
			(layer "B.Fab")
			(hide yes)
			(effects
				(font
					(size 1.27 1.27)
					(thickness 0.15)
				)
				(justify mirror)
			)
		)
		(property "Description" "SMD Chip Resistor, 200 ohm, ± 1%, 62.5 mW, 0402 [1005 Metric], Thick Film, General Purpose"
			(at 0 0 90)
			(layer "B.Fab")
			(hide yes)
			(effects
				(font
					(size 1.27 1.27)
					(thickness 0.15)
				)
				(justify mirror)
			)
		)
		(property "MPN" "CR0402-FX-2000GLF"
			(at 0 0 270)
			(unlocked yes)
			(layer "B.Fab")
			(hide yes)
			(effects
				(font
					(size 1 1)
					(thickness 0.15)
				)
				(justify mirror)
			)
		)
		(property "Manufacturer" "Bourns"
			(at 0 0 270)
			(unlocked yes)
			(layer "B.Fab")
			(hide yes)
			(effects
				(font
					(size 1 1)
					(thickness 0.15)
				)
				(justify mirror)
			)
		)
		(property "License" "Apache-2.0"
			(at 0 0 270)
			(unlocked yes)
			(layer "B.Fab")
			(hide yes)
			(effects
				(font
					(size 1 1)
					(thickness 0.15)
				)
				(justify mirror)
			)
		)
		(property "Author" "Antmicro"
			(at 0 0 270)
			(unlocked yes)
			(layer "B.Fab")
			(hide yes)
			(effects
				(font
					(size 1 1)
					(thickness 0.15)
				)
				(justify mirror)
			)
		)
		(property "Val" "200R"
			(at 0 0 270)
			(unlocked yes)
			(layer "B.Fab")
			(hide yes)
			(effects
				(font
					(size 1 1)
					(thickness 0.15)
				)
				(justify mirror)
			)
		)
		(property "Tolerance" "1%"
			(at 0 0 270)
			(unlocked yes)
			(layer "B.Fab")
			(hide yes)
			(effects
				(font
					(size 1 1)
					(thickness 0.15)
				)
				(justify mirror)
			)
		)
		(sheetname "/M.2/")
		(sheetfile "m2.kicad_sch")
		(attr smd)
		(fp_rect
			(start -0.925 0.47)
			(end 0.925 -0.47)
			(stroke
				(width 0.05)
				(type default)
			)
			(fill no)
			(layer "B.CrtYd")
		)
		(fp_rect
			(start -0.5 0.25)
			(end 0.5 -0.25)
			(stroke
				(width 0.15)
				(type solid)
			)
			(fill no)
			(layer "B.Fab")
		)
		(fp_text user "Author: Antmicro"
			(at -0.95 -4.169 90)
			(layer "B.Fab")
			(effects
				(font
					(size 0.7 0.7)
					(thickness 0.15)
				)
				(justify right top mirror)
			)
		)
		(fp_text user "License: Apache-2.0"
			(at -0.95 -5.169 90)
			(layer "B.Fab")
			(effects
				(font
					(size 0.7 0.7)
					(thickness 0.15)
				)
				(justify right top mirror)
			)
		)
		(fp_text user "${REFERENCE}"
			(at -0.95 -3.168 90)
			(layer "B.Fab")
			(effects
				(font
					(size 0.7 0.7)
					(thickness 0.15)
				)
				(justify right top mirror)
			)
		)
		(pad "1" smd roundrect
			(at -0.48 0 90)
			(size 0.59 0.64)
			(layers "B.Cu" "B.Mask" "B.Paste")
			(roundrect_rratio 0.25)
			(net 546 "Net-(D34-A)")
			(pintype "passive")
		)
		(pad "2" smd roundrect
			(at 0.48 0 90)
			(size 0.59 0.64)
			(layers "B.Cu" "B.Mask" "B.Paste")
			(roundrect_rratio 0.25)
			(net 2 "+3V3")
			(pintype "passive")
		)
	)
	(footprint "antmicro-footprints:TP_SMD_0.75mm"
		(layer "B.Cu")
		(at 232.3 75 180)
		(property "Reference" "TP62"
			(at 0 0.6 0)
			(layer "B.SilkS")
			(effects
				(font
					(size 0.7 0.7)
					(thickness 0.15)
				)
				(justify left bottom mirror)
			)
		)
		(property "Value" "TP_0.75mm_SMD"
			(at 0 -1.2 0)
			(layer "B.Fab")
			(effects
				(font
					(size 0.7 0.7)
					(thickness 0.15)
				)
				(justify left bottom mirror)
			)
		)
		(property "Description" "SMT test point"
			(at 0 0 0)
			(layer "B.Fab")
			(hide yes)
			(effects
				(font
					(size 1.27 1.27)
					(thickness 0.15)
				)
				(justify mirror)
			)
		)
		(property "MPN" ""
			(at 0 0 0)
			(unlocked yes)
			(layer "B.Fab")
			(hide yes)
			(effects
				(font
					(size 1 1)
					(thickness 0.15)
				)
				(justify mirror)
			)
		)
		(property "Manufacturer" ""
			(at 0 0 0)
			(unlocked yes)
			(layer "B.Fab")
			(hide yes)
			(effects
				(font
					(size 1 1)
					(thickness 0.15)
				)
				(justify mirror)
			)
		)
		(property "Author" "Antmicro"
			(at 0 0 0)
			(unlocked yes)
			(layer "B.Fab")
			(hide yes)
			(effects
				(font
					(size 1 1)
					(thickness 0.15)
				)
				(justify mirror)
			)
		)
		(property "License" "Apache-2.0"
			(at 0 0 0)
			(unlocked yes)
			(layer "B.Fab")
			(hide yes)
			(effects
				(font
					(size 1 1)
					(thickness 0.15)
				)
				(justify mirror)
			)
		)
		(sheetname "/USB Debug, PD/")
		(sheetfile "usb_debug_pd.kicad_sch")
		(attr exclude_from_pos_files exclude_from_bom)
		(fp_circle
			(center 0 0)
			(end 0.475 0)
			(stroke
				(width 0.05)
				(type default)
			)
			(fill no)
			(layer "B.CrtYd")
		)
		(fp_text user "License: Apache-2.0"
			(at -0.4 -5.101 0)
			(layer "B.Fab")
			(effects
				(font
					(size 0.7 0.7)
					(thickness 0.15)
				)
				(justify left bottom mirror)
			)
		)
		(fp_text user "Author: Antmicro"
			(at -0.4 -3.901 0)
			(layer "B.Fab")
			(effects
				(font
					(size 0.7 0.7)
					(thickness 0.15)
				)
				(justify left bottom mirror)
			)
		)
		(fp_text user "${REFERENCE}"
			(at -0.4 -2.7 0)
			(layer "B.Fab")
			(effects
				(font
					(size 0.7 0.7)
					(thickness 0.15)
				)
				(justify left bottom mirror)
			)
		)
		(pad "1" smd circle
			(at 0 0 180)
			(size 0.75 0.75)
			(layers "B.Cu" "B.Mask")
			(net 176 "/USB Debug, PD/USBC0_VBUS")
			(pinfunction "1")
			(pintype "passive")
		)
	)
	(footprint "antmicro-footprints:SOD-523"
		(layer "B.Cu")
		(at 219.13 113.56 90)
		(property "Reference" "D57"
			(at -3.24 -0.43 90)
			(layer "B.SilkS")
			(effects
				(font
					(size 0.7 0.7)
					(thickness 0.15)
				)
				(justify right top mirror)
			)
		)
		(property "Value" "RB521S30T1G"
			(at 0 -1.499 90)
			(layer "B.Fab")
			(effects
				(font
					(size 0.7 0.7)
					(thickness 0.15)
				)
				(justify right top mirror)
			)
		)
		(property "Datasheet" "https://www.onsemi.com/pdf/datasheet/rb521s30t1-d.pdf"
			(at 0 0 90)
			(layer "B.Fab")
			(hide yes)
			(effects
				(font
					(size 1.27 1.27)
					(thickness 0.15)
				)
				(justify mirror)
			)
		)
		(property "Description" "Small Signal Schottky Diode, Single, 30 V, 200 mA, 500 mV, 1 A, 125 °C"
			(at 0 0 90)
			(layer "B.Fab")
			(hide yes)
			(effects
				(font
					(size 1.27 1.27)
					(thickness 0.15)
				)
				(justify mirror)
			)
		)
		(property "MPN" "RB521S30T1G"
			(at 0 0 270)
			(unlocked yes)
			(layer "B.Fab")
			(hide yes)
			(effects
				(font
					(size 1 1)
					(thickness 0.15)
				)
				(justify mirror)
			)
		)
		(property "Manufacturer" "ON Semiconductor"
			(at 0 0 270)
			(unlocked yes)
			(layer "B.Fab")
			(hide yes)
			(effects
				(font
					(size 1 1)
					(thickness 0.15)
				)
				(justify mirror)
			)
		)
		(property "Author" "Antmicro"
			(at 0 0 270)
			(unlocked yes)
			(layer "B.Fab")
			(hide yes)
			(effects
				(font
					(size 1 1)
					(thickness 0.15)
				)
				(justify mirror)
			)
		)
		(property "License" "Apache-2.0"
			(at 0 0 270)
			(unlocked yes)
			(layer "B.Fab")
			(hide yes)
			(effects
				(font
					(size 1 1)
					(thickness 0.15)
				)
				(justify mirror)
			)
		)
		(sheetname "/USB Hub/")
		(sheetfile "usb_hub.kicad_sch")
		(attr smd)
		(fp_line
			(start -0.35 0.5)
			(end -0.35 -0.5)
			(stroke
				(width 0.15)
				(type solid)
			)
			(layer "B.SilkS")
		)
		(fp_rect
			(start -1 0.6)
			(end 1 -0.6)
			(stroke
				(width 0.05)
				(type solid)
			)
			(fill no)
			(layer "B.CrtYd")
		)
		(fp_line
			(start -0.652 -0.423)
			(end 0.65 -0.423)
			(stroke
				(width 0.15)
				(type solid)
			)
			(layer "B.Fab")
		)
		(fp_line
			(start -0.652 -0.423)
			(end -0.652 0.425)
			(stroke
				(width 0.15)
				(type solid)
			)
			(layer "B.Fab")
		)
		(fp_line
			(start -0.35 0.4)
			(end -0.35 -0.4)
			(stroke
				(width 0.15)
				(type solid)
			)
			(layer "B.Fab")
		)
		(fp_line
			(start 0.65 0.425)
			(end 0.65 -0.423)
			(stroke
				(width 0.15)
				(type solid)
			)
			(layer "B.Fab")
		)
		(fp_line
			(start -0.652 0.425)
			(end 0.65 0.425)
			(stroke
				(width 0.15)
				(type solid)
			)
			(layer "B.Fab")
		)
		(fp_text user "Author: Antmicro"
			(at -1.276 -4.7 90)
			(layer "B.Fab")
			(effects
				(font
					(size 0.7 0.7)
					(thickness 0.15)
				)
				(justify right top mirror)
			)
		)
		(fp_text user "${REFERENCE}"
			(at -1.276 -3.499 90)
			(layer "B.Fab")
			(effects
				(font
					(size 0.7 0.7)
					(thickness 0.15)
				)
				(justify right top mirror)
			)
		)
		(fp_text user "License: Apache-2.0"
			(at -1.276 -5.9 90)
			(layer "B.Fab")
			(effects
				(font
					(size 0.7 0.7)
					(thickness 0.15)
				)
				(justify right top mirror)
			)
		)
		(pad "1" smd roundrect
			(at -0.701 0 90)
			(size 0.5 0.6)
			(layers "B.Cu" "B.Mask" "B.Paste")
			(roundrect_rratio 0.25)
			(net 633 "Net-(D57-C)")
			(pinfunction "C")
			(pintype "passive")
		)
		(pad "2" smd roundrect
			(at 0.699 0 90)
			(size 0.5 0.6)
			(layers "B.Cu" "B.Mask" "B.Paste")
			(roundrect_rratio 0.25)
			(net 1019 "Net-(D57-A)")
			(pinfunction "A")
			(pintype "passive")
		)
	)
	(footprint "antmicro-footprints:R_0402_1005Metric"
		(layer "B.Cu")
		(at 135.8 65.2 90)
		(descr "Resistor SMD 0402")
		(tags "resistor SMD 0402")
		(property "Reference" "R241"
			(at -3.8 -0.5 90)
			(layer "B.SilkS")
			(effects
				(font
					(size 0.7 0.7)
					(thickness 0.15)
				)
				(justify right top mirror)
			)
		)
		(property "Value" "R_10k_0402"
			(at -1.011843 -1.772047 90)
			(layer "B.Fab")
			(effects
				(font
					(size 0.7 0.7)
					(thickness 0.15)
				)
				(justify right top mirror)
			)
		)
		(property "Datasheet" "https://www.bourns.com/docs/product-datasheets/cr.pdf"
			(at 0 0 90)
			(layer "B.Fab")
			(hide yes)
			(effects
				(font
					(size 1.27 1.27)
					(thickness 0.15)
				)
				(justify mirror)
			)
		)
		(property "Description" "SMD Chip Resistor, 10 kohm, ± 1%, 62.5 mW, 0402 [1005 Metric], Thick Film, General Purpose"
			(at 0 0 90)
			(layer "B.Fab")
			(hide yes)
			(effects
				(font
					(size 1.27 1.27)
					(thickness 0.15)
				)
				(justify mirror)
			)
		)
		(property "Manufacturer" "Bourns"
			(at 0 0 270)
			(unlocked yes)
			(layer "B.Fab")
			(hide yes)
			(effects
				(font
					(size 1 1)
					(thickness 0.15)
				)
				(justify mirror)
			)
		)
		(property "MPN" "CR0402-FX-1002GLF"
			(at 0 0 270)
			(unlocked yes)
			(layer "B.Fab")
			(hide yes)
			(effects
				(font
					(size 1 1)
					(thickness 0.15)
				)
				(justify mirror)
			)
		)
		(property "Val" "10k"
			(at 0 0 270)
			(unlocked yes)
			(layer "B.Fab")
			(hide yes)
			(effects
				(font
					(size 1 1)
					(thickness 0.15)
				)
				(justify mirror)
			)
		)
		(property "License" "Apache-2.0"
			(at 0 0 270)
			(unlocked yes)
			(layer "B.Fab")
			(hide yes)
			(effects
				(font
					(size 1 1)
					(thickness 0.15)
				)
				(justify mirror)
			)
		)
		(property "Author" "Antmicro"
			(at 0 0 270)
			(unlocked yes)
			(layer "B.Fab")
			(hide yes)
			(effects
				(font
					(size 1 1)
					(thickness 0.15)
				)
				(justify mirror)
			)
		)
		(property "Tolerance" "1%"
			(at 0 0 270)
			(unlocked yes)
			(layer "B.Fab")
			(hide yes)
			(effects
				(font
					(size 1 1)
					(thickness 0.15)
				)
				(justify mirror)
			)
		)
		(sheetname "/Peripherals/")
		(sheetfile "peripherals.kicad_sch")
		(attr smd)
		(fp_rect
			(start -0.925 0.47)
			(end 0.925 -0.47)
			(stroke
				(width 0.05)
				(type default)
			)
			(fill no)
			(layer "B.CrtYd")
		)
		(fp_rect
			(start -0.5 0.25)
			(end 0.5 -0.25)
			(stroke
				(width 0.15)
				(type solid)
			)
			(fill no)
			(layer "B.Fab")
		)
		(fp_text user "${REFERENCE}"
			(at -0.95 -3.168 90)
			(layer "B.Fab")
			(effects
				(font
					(size 0.7 0.7)
					(thickness 0.15)
				)
				(justify right top mirror)
			)
		)
		(fp_text user "License: Apache-2.0"
			(at -0.95 -5.169 90)
			(layer "B.Fab")
			(effects
				(font
					(size 0.7 0.7)
					(thickness 0.15)
				)
				(justify right top mirror)
			)
		)
		(fp_text user "Author: Antmicro"
			(at -0.95 -4.169 90)
			(layer "B.Fab")
			(effects
				(font
					(size 0.7 0.7)
					(thickness 0.15)
				)
				(justify right top mirror)
			)
		)
		(pad "1" smd roundrect
			(at -0.48 0 90)
			(size 0.59 0.64)
			(layers "B.Cu" "B.Mask" "B.Paste")
			(roundrect_rratio 0.25)
			(net 1 "GND")
			(pintype "passive")
		)
		(pad "2" smd roundrect
			(at 0.48 0 90)
			(size 0.59 0.64)
			(layers "B.Cu" "B.Mask" "B.Paste")
			(roundrect_rratio 0.25)
			(net 1009 "Net-(U53-ISET)")
			(pintype "passive")
		)
	)
	(footprint "antmicro-footprints:TP_SMD_0.75mm"
		(layer "B.Cu")
		(at 180.89 58 180)
		(property "Reference" "TP126"
			(at -0.43 4.03 90)
			(layer "B.SilkS")
			(effects
				(font
					(size 0.7 0.7)
					(thickness 0.15)
				)
				(justify left bottom mirror)
			)
		)
		(property "Value" "TP_0.75mm_SMD"
			(at 0 -1.2 0)
			(layer "B.Fab")
			(effects
				(font
					(size 0.7 0.7)
					(thickness 0.15)
				)
				(justify left bottom mirror)
			)
		)
		(property "Description" "SMT test point"
			(at 0 0 0)
			(layer "B.Fab")
			(hide yes)
			(effects
				(font
					(size 1.27 1.27)
					(thickness 0.15)
				)
				(justify mirror)
			)
		)
		(property "MPN" ""
			(at 0 0 0)
			(unlocked yes)
			(layer "B.Fab")
			(hide yes)
			(effects
				(font
					(size 1 1)
					(thickness 0.15)
				)
				(justify mirror)
			)
		)
		(property "Manufacturer" ""
			(at 0 0 0)
			(unlocked yes)
			(layer "B.Fab")
			(hide yes)
			(effects
				(font
					(size 1 1)
					(thickness 0.15)
				)
				(justify mirror)
			)
		)
		(property "Author" "Antmicro"
			(at 0 0 0)
			(unlocked yes)
			(layer "B.Fab")
			(hide yes)
			(effects
				(font
					(size 1 1)
					(thickness 0.15)
				)
				(justify mirror)
			)
		)
		(property "License" "Apache-2.0"
			(at 0 0 0)
			(unlocked yes)
			(layer "B.Fab")
			(hide yes)
			(effects
				(font
					(size 1 1)
					(thickness 0.15)
				)
				(justify mirror)
			)
		)
		(sheetname "/Power/")
		(sheetfile "power.kicad_sch")
		(attr exclude_from_pos_files exclude_from_bom)
		(fp_circle
			(center 0 0)
			(end 0.475 0)
			(stroke
				(width 0.05)
				(type default)
			)
			(fill no)
			(layer "B.CrtYd")
		)
		(fp_text user "Author: Antmicro"
			(at -0.4 -3.901 0)
			(layer "B.Fab")
			(effects
				(font
					(size 0.7 0.7)
					(thickness 0.15)
				)
				(justify left bottom mirror)
			)
		)
		(fp_text user "License: Apache-2.0"
			(at -0.4 -5.101 0)
			(layer "B.Fab")
			(effects
				(font
					(size 0.7 0.7)
					(thickness 0.15)
				)
				(justify left bottom mirror)
			)
		)
		(fp_text user "${REFERENCE}"
			(at -0.4 -2.7 0)
			(layer "B.Fab")
			(effects
				(font
					(size 0.7 0.7)
					(thickness 0.15)
				)
				(justify left bottom mirror)
			)
		)
		(pad "1" smd circle
			(at 0 0 180)
			(size 0.75 0.75)
			(layers "B.Cu" "B.Mask")
			(net 12 "SYS_VIN_HV")
			(pinfunction "1")
			(pintype "passive")
		)
	)
)
